(kicad_pcb
	(version 20260206)
	(generator "pcbnew")
	(generator_version "10.0")
	(general
		(thickness 1.6)
		(legacy_teardrops no)
	)
	(paper "A4")
	(title_block
		(title "03242023_DA0F0TMBIJ0_F0T_Motherboard_J_brd_V01_OCP.brd")
		(comment 1 "Grand Teton / footprints 1683-1688 of 6105")
	)
	(layers
		(0 "F.Cu" signal "TOP")
		(4 "In1.Cu" signal "GND")
		(6 "In2.Cu" signal "IN1")
		(8 "In3.Cu" signal "GND1")
		(10 "In4.Cu" signal "IN2")
		(12 "In5.Cu" signal "GND2")
		(14 "In6.Cu" signal "IN3")
		(16 "In7.Cu" signal "GND3")
		(18 "In8.Cu" signal "VCC")
		(20 "In9.Cu" signal "VCC1")
		(22 "In10.Cu" signal "GND4")
		(24 "In11.Cu" signal "IN4")
		(26 "In12.Cu" signal "GND5")
		(28 "In13.Cu" signal "IN5")
		(30 "In14.Cu" signal "GND6")
		(32 "In15.Cu" signal "IN6")
		(34 "In16.Cu" signal "GND7")
		(2 "B.Cu" signal "BOTTOM")
		(9 "F.Adhes" user "F.Adhesive")
		(11 "B.Adhes" user "B.Adhesive")
		(13 "F.Paste" user "Package Geometry/Pastemask Top")
		(15 "B.Paste" user "Package Geometry/Pastemask Bottom")
		(5 "F.SilkS" user "Ref Des/Silkscreen Top")
		(7 "B.SilkS" user "Ref Des/Silkscreen Bottom")
		(1 "F.Mask" user "Board Geometry/Soldermask Top")
		(3 "B.Mask" user "Board Geometry/Soldermask Bottom")
		(17 "Dwgs.User" user "User.Drawings")
		(19 "Cmts.User" user "User.Comments")
		(21 "Eco1.User" user "User.Eco1")
		(23 "Eco2.User" user "User.Eco2")
		(25 "Edge.Cuts" user "Board Geometry/Outline")
		(27 "Margin" user)
		(31 "F.CrtYd" user "Package Geometry/Place Bound Top")
		(29 "B.CrtYd" user "Package Geometry/Place Bound Bottom")
		(35 "F.Fab" user "Ref Des/Assembly Top")
		(33 "B.Fab" user "Ref Des/Assembly Bottom")
	)
	(footprint ""
		(layer "F.Cu")
		(at 368.1984 -101.171248 -90)
		(property "Reference" "R1381"
			(at 0 0 270)
			(layer "F.SilkS")
			(hide yes)
			(effects
				(font
					(size 1.27 1.27)
				)
			)
		)
		(property "Value" ""
			(at 0 0 270)
			(layer "F.Fab")
			(effects
				(font
					(size 1.27 1.27)
				)
			)
		)
		(duplicate_pad_numbers_are_jumpers no)
		(fp_line
			(start -0.7874 0.4064)
			(end -0.7874 -0.4064)
			(stroke
				(width 0.1524)
				(type default)
			)
			(layer "F.SilkS")
		)
		(fp_line
			(start 0.7874 0.4064)
			(end -0.7874 0.4064)
			(stroke
				(width 0.1524)
				(type default)
			)
			(layer "F.SilkS")
		)
		(fp_line
			(start -0.7874 -0.4064)
			(end 0.7874 -0.4064)
			(stroke
				(width 0.1524)
				(type default)
			)
			(layer "F.SilkS")
		)
		(fp_line
			(start 0.7874 -0.4064)
			(end 0.7874 0.4064)
			(stroke
				(width 0.1524)
				(type default)
			)
			(layer "F.SilkS")
		)
		(fp_line
			(start -0.67945 0.3048)
			(end -0.67945 -0.305054)
			(stroke
				(width 0.1)
				(type default)
			)
			(layer "F.Fab")
		)
		(fp_line
			(start -0.12065 0.3048)
			(end -0.67945 0.3048)
			(stroke
				(width 0.1)
				(type default)
			)
			(layer "F.Fab")
		)
		(fp_line
			(start 0.120396 0.3048)
			(end 0.120396 0.2794)
			(stroke
				(width 0.1)
				(type default)
			)
			(layer "F.Fab")
		)
		(fp_line
			(start 0.67945 0.3048)
			(end 0.120396 0.3048)
			(stroke
				(width 0.1)
				(type default)
			)
			(layer "F.Fab")
		)
		(fp_line
			(start -0.12065 0.2794)
			(end -0.12065 0.3048)
			(stroke
				(width 0.1)
				(type default)
			)
			(layer "F.Fab")
		)
		(fp_line
			(start 0.120396 0.2794)
			(end -0.12065 0.2794)
			(stroke
				(width 0.1)
				(type default)
			)
			(layer "F.Fab")
		)
		(fp_line
			(start -0.12065 -0.2794)
			(end 0.12065 -0.2794)
			(stroke
				(width 0.1)
				(type default)
			)
			(layer "F.Fab")
		)
		(fp_line
			(start 0.12065 -0.2794)
			(end 0.12065 -0.3048)
			(stroke
				(width 0.1)
				(type default)
			)
			(layer "F.Fab")
		)
		(fp_line
			(start 0.12065 -0.3048)
			(end 0.67945 -0.3048)
			(stroke
				(width 0.1)
				(type default)
			)
			(layer "F.Fab")
		)
		(fp_line
			(start 0.67945 -0.3048)
			(end 0.67945 0.3048)
			(stroke
				(width 0.1)
				(type default)
			)
			(layer "F.Fab")
		)
		(fp_line
			(start -0.67945 -0.305054)
			(end -0.12065 -0.305054)
			(stroke
				(width 0.1)
				(type default)
			)
			(layer "F.Fab")
		)
		(fp_line
			(start -0.12065 -0.305054)
			(end -0.12065 -0.2794)
			(stroke
				(width 0.1)
				(type default)
			)
			(layer "F.Fab")
		)
		(pad "1" smd circle
			(at -0.40005 0 270)
			(size 0 0)
			(layers "F.Cu" "F.Mask" "F.Paste")
			(net "P3V3_AUX")
		)
		(pad "2" smd circle
			(at 0.40005 0 270)
			(size 0 0)
			(layers "F.Cu" "F.Mask" "F.Paste")
			(net "FM_BMC_CPU_FBRK_OUT_N")
		)
	)
	(footprint ""
		(layer "F.Cu")
		(at 120.37822 -417.383468)
		(property "Reference" "R3509"
			(at 0 0 0)
			(layer "F.SilkS")
			(hide yes)
			(effects
				(font
					(size 1.27 1.27)
				)
			)
		)
		(property "Value" ""
			(at 0 0 0)
			(layer "F.Fab")
			(effects
				(font
					(size 1.27 1.27)
				)
			)
		)
		(duplicate_pad_numbers_are_jumpers no)
		(fp_line
			(start -0.7874 -0.4064)
			(end 0.7874 -0.4064)
			(stroke
				(width 0.1524)
				(type default)
			)
			(layer "F.SilkS")
		)
		(fp_line
			(start -0.7874 0.4064)
			(end -0.7874 -0.4064)
			(stroke
				(width 0.1524)
				(type default)
			)
			(layer "F.SilkS")
		)
		(fp_line
			(start 0.7874 -0.4064)
			(end 0.7874 0.4064)
			(stroke
				(width 0.1524)
				(type default)
			)
			(layer "F.SilkS")
		)
		(fp_line
			(start 0.7874 0.4064)
			(end -0.7874 0.4064)
			(stroke
				(width 0.1524)
				(type default)
			)
			(layer "F.SilkS")
		)
		(fp_line
			(start -0.67945 -0.305054)
			(end -0.12065 -0.305054)
			(stroke
				(width 0.1)
				(type default)
			)
			(layer "F.Fab")
		)
		(fp_line
			(start -0.67945 0.3048)
			(end -0.67945 -0.305054)
			(stroke
				(width 0.1)
				(type default)
			)
			(layer "F.Fab")
		)
		(fp_line
			(start -0.12065 -0.305054)
			(end -0.12065 -0.2794)
			(stroke
				(width 0.1)
				(type default)
			)
			(layer "F.Fab")
		)
		(fp_line
			(start -0.12065 -0.2794)
			(end 0.12065 -0.2794)
			(stroke
				(width 0.1)
				(type default)
			)
			(layer "F.Fab")
		)
		(fp_line
			(start -0.12065 0.2794)
			(end -0.12065 0.3048)
			(stroke
				(width 0.1)
				(type default)
			)
			(layer "F.Fab")
		)
		(fp_line
			(start -0.12065 0.3048)
			(end -0.67945 0.3048)
			(stroke
				(width 0.1)
				(type default)
			)
			(layer "F.Fab")
		)
		(fp_line
			(start 0.120396 0.2794)
			(end -0.12065 0.2794)
			(stroke
				(width 0.1)
				(type default)
			)
			(layer "F.Fab")
		)
		(fp_line
			(start 0.120396 0.3048)
			(end 0.120396 0.2794)
			(stroke
				(width 0.1)
				(type default)
			)
			(layer "F.Fab")
		)
		(fp_line
			(start 0.12065 -0.3048)
			(end 0.67945 -0.3048)
			(stroke
				(width 0.1)
				(type default)
			)
			(layer "F.Fab")
		)
		(fp_line
			(start 0.12065 -0.2794)
			(end 0.12065 -0.3048)
			(stroke
				(width 0.1)
				(type default)
			)
			(layer "F.Fab")
		)
		(fp_line
			(start 0.67945 -0.3048)
			(end 0.67945 0.3048)
			(stroke
				(width 0.1)
				(type default)
			)
			(layer "F.Fab")
		)
		(fp_line
			(start 0.67945 0.3048)
			(end 0.120396 0.3048)
			(stroke
				(width 0.1)
				(type default)
			)
			(layer "F.Fab")
		)
		(pad "1" smd circle
			(at -0.40005 0)
			(size 0 0)
			(layers "F.Cu" "F.Mask" "F.Paste")
			(net "GPU_FPGA_RST_R1_BUF_N")
		)
		(pad "2" smd circle
			(at 0.40005 0)
			(size 0 0)
			(layers "F.Cu" "F.Mask" "F.Paste")
			(net "GND")
		)
	)
	(footprint ""
		(layer "F.Cu")
		(at 277.64994 -96.329754)
		(property "Reference" "R721"
			(at 0 0 0)
			(layer "F.SilkS")
			(hide yes)
			(effects
				(font
					(size 1.27 1.27)
				)
			)
		)
		(property "Value" ""
			(at 0 0 0)
			(layer "F.Fab")
			(effects
				(font
					(size 1.27 1.27)
				)
			)
		)
		(duplicate_pad_numbers_are_jumpers no)
		(fp_line
			(start -0.7874 -0.4064)
			(end 0.7874 -0.4064)
			(stroke
				(width 0.1524)
				(type default)
			)
			(layer "F.SilkS")
		)
		(fp_line
			(start -0.7874 0.4064)
			(end -0.7874 -0.4064)
			(stroke
				(width 0.1524)
				(type default)
			)
			(layer "F.SilkS")
		)
		(fp_line
			(start 0.7874 -0.4064)
			(end 0.7874 0.4064)
			(stroke
				(width 0.1524)
				(type default)
			)
			(layer "F.SilkS")
		)
		(fp_line
			(start 0.7874 0.4064)
			(end -0.7874 0.4064)
			(stroke
				(width 0.1524)
				(type default)
			)
			(layer "F.SilkS")
		)
		(fp_line
			(start -0.67945 -0.305054)
			(end -0.12065 -0.305054)
			(stroke
				(width 0.1)
				(type default)
			)
			(layer "F.Fab")
		)
		(fp_line
			(start -0.67945 0.3048)
			(end -0.67945 -0.305054)
			(stroke
				(width 0.1)
				(type default)
			)
			(layer "F.Fab")
		)
		(fp_line
			(start -0.12065 -0.305054)
			(end -0.12065 -0.2794)
			(stroke
				(width 0.1)
				(type default)
			)
			(layer "F.Fab")
		)
		(fp_line
			(start -0.12065 -0.2794)
			(end 0.12065 -0.2794)
			(stroke
				(width 0.1)
				(type default)
			)
			(layer "F.Fab")
		)
		(fp_line
			(start -0.12065 0.2794)
			(end -0.12065 0.3048)
			(stroke
				(width 0.1)
				(type default)
			)
			(layer "F.Fab")
		)
		(fp_line
			(start -0.12065 0.3048)
			(end -0.67945 0.3048)
			(stroke
				(width 0.1)
				(type default)
			)
			(layer "F.Fab")
		)
		(fp_line
			(start 0.120396 0.2794)
			(end -0.12065 0.2794)
			(stroke
				(width 0.1)
				(type default)
			)
			(layer "F.Fab")
		)
		(fp_line
			(start 0.120396 0.3048)
			(end 0.120396 0.2794)
			(stroke
				(width 0.1)
				(type default)
			)
			(layer "F.Fab")
		)
		(fp_line
			(start 0.12065 -0.3048)
			(end 0.67945 -0.3048)
			(stroke
				(width 0.1)
				(type default)
			)
			(layer "F.Fab")
		)
		(fp_line
			(start 0.12065 -0.2794)
			(end 0.12065 -0.3048)
			(stroke
				(width 0.1)
				(type default)
			)
			(layer "F.Fab")
		)
		(fp_line
			(start 0.67945 -0.3048)
			(end 0.67945 0.3048)
			(stroke
				(width 0.1)
				(type default)
			)
			(layer "F.Fab")
		)
		(fp_line
			(start 0.67945 0.3048)
			(end 0.120396 0.3048)
			(stroke
				(width 0.1)
				(type default)
			)
			(layer "F.Fab")
		)
		(pad "1" smd circle
			(at -0.40005 0)
			(size 0 0)
			(layers "F.Cu" "F.Mask" "F.Paste")
			(net "P3V3_AUX")
		)
		(pad "2" smd circle
			(at 0.40005 0)
			(size 0 0)
			(layers "F.Cu" "F.Mask" "F.Paste")
			(net "MB_FRU_ADDR0")
		)
	)
	(footprint ""
		(layer "F.Cu")
		(at 135.05688 -92.674948 -90)
		(property "Reference" "R4408"
			(at 0 0 270)
			(layer "F.SilkS")
			(hide yes)
			(effects
				(font
					(size 1.27 1.27)
				)
			)
		)
		(property "Value" ""
			(at 0 0 270)
			(layer "F.Fab")
			(effects
				(font
					(size 1.27 1.27)
				)
			)
		)
		(duplicate_pad_numbers_are_jumpers no)
		(fp_line
			(start -0.7874 0.4064)
			(end -0.7874 -0.4064)
			(stroke
				(width 0.1524)
				(type default)
			)
			(layer "F.SilkS")
		)
		(fp_line
			(start 0.7874 0.4064)
			(end -0.7874 0.4064)
			(stroke
				(width 0.1524)
				(type default)
			)
			(layer "F.SilkS")
		)
		(fp_line
			(start -0.7874 -0.4064)
			(end 0.7874 -0.4064)
			(stroke
				(width 0.1524)
				(type default)
			)
			(layer "F.SilkS")
		)
		(fp_line
			(start 0.7874 -0.4064)
			(end 0.7874 0.4064)
			(stroke
				(width 0.1524)
				(type default)
			)
			(layer "F.SilkS")
		)
		(fp_line
			(start -0.67945 0.3048)
			(end -0.67945 -0.305054)
			(stroke
				(width 0.1)
				(type default)
			)
			(layer "F.Fab")
		)
		(fp_line
			(start -0.12065 0.3048)
			(end -0.67945 0.3048)
			(stroke
				(width 0.1)
				(type default)
			)
			(layer "F.Fab")
		)
		(fp_line
			(start 0.120396 0.3048)
			(end 0.120396 0.2794)
			(stroke
				(width 0.1)
				(type default)
			)
			(layer "F.Fab")
		)
		(fp_line
			(start 0.67945 0.3048)
			(end 0.120396 0.3048)
			(stroke
				(width 0.1)
				(type default)
			)
			(layer "F.Fab")
		)
		(fp_line
			(start -0.12065 0.2794)
			(end -0.12065 0.3048)
			(stroke
				(width 0.1)
				(type default)
			)
			(layer "F.Fab")
		)
		(fp_line
			(start 0.120396 0.2794)
			(end -0.12065 0.2794)
			(stroke
				(width 0.1)
				(type default)
			)
			(layer "F.Fab")
		)
		(fp_line
			(start -0.12065 -0.2794)
			(end 0.12065 -0.2794)
			(stroke
				(width 0.1)
				(type default)
			)
			(layer "F.Fab")
		)
		(fp_line
			(start 0.12065 -0.2794)
			(end 0.12065 -0.3048)
			(stroke
				(width 0.1)
				(type default)
			)
			(layer "F.Fab")
		)
		(fp_line
			(start 0.12065 -0.3048)
			(end 0.67945 -0.3048)
			(stroke
				(width 0.1)
				(type default)
			)
			(layer "F.Fab")
		)
		(fp_line
			(start 0.67945 -0.3048)
			(end 0.67945 0.3048)
			(stroke
				(width 0.1)
				(type default)
			)
			(layer "F.Fab")
		)
		(fp_line
			(start -0.67945 -0.305054)
			(end -0.12065 -0.305054)
			(stroke
				(width 0.1)
				(type default)
			)
			(layer "F.Fab")
		)
		(fp_line
			(start -0.12065 -0.305054)
			(end -0.12065 -0.2794)
			(stroke
				(width 0.1)
				(type default)
			)
			(layer "F.Fab")
		)
		(pad "1" smd circle
			(at -0.40005 0 270)
			(size 0 0)
			(layers "F.Cu" "F.Mask" "F.Paste")
			(net "H_CPU1_MEMHOT_OUT_VT_N")
		)
		(pad "2" smd circle
			(at 0.40005 0 270)
			(size 0 0)
			(layers "F.Cu" "F.Mask" "F.Paste")
			(net "H_CPU1_MEMHOT_OUT_LVC1_N")
		)
	)
	(footprint ""
		(layer "F.Cu")
		(at 28.578048 -76.289916)
		(property "Reference" "C1809"
			(at 0 0 0)
			(layer "F.SilkS")
			(hide yes)
			(effects
				(font
					(size 1.27 1.27)
				)
			)
		)
		(property "Value" ""
			(at 0 0 0)
			(layer "F.Fab")
			(effects
				(font
					(size 1.27 1.27)
				)
			)
		)
		(duplicate_pad_numbers_are_jumpers no)
		(fp_line
			(start -0.7874 -0.4064)
			(end 0.7874 -0.4064)
			(stroke
				(width 0.1524)
				(type default)
			)
			(layer "F.SilkS")
		)
		(fp_line
			(start -0.7874 0.4064)
			(end -0.7874 -0.4064)
			(stroke
				(width 0.1524)
				(type default)
			)
			(layer "F.SilkS")
		)
		(fp_line
			(start 0.7874 -0.4064)
			(end 0.7874 0.4064)
			(stroke
				(width 0.1524)
				(type default)
			)
			(layer "F.SilkS")
		)
		(fp_line
			(start 0.7874 0.4064)
			(end -0.7874 0.4064)
			(stroke
				(width 0.1524)
				(type default)
			)
			(layer "F.SilkS")
		)
		(fp_line
			(start -0.67945 -0.305054)
			(end -0.12065 -0.305054)
			(stroke
				(width 0.1)
				(type default)
			)
			(layer "F.Fab")
		)
		(fp_line
			(start -0.67945 0.3048)
			(end -0.67945 -0.305054)
			(stroke
				(width 0.1)
				(type default)
			)
			(layer "F.Fab")
		)
		(fp_line
			(start -0.12065 -0.305054)
			(end -0.12065 -0.2794)
			(stroke
				(width 0.1)
				(type default)
			)
			(layer "F.Fab")
		)
		(fp_line
			(start -0.12065 -0.2794)
			(end 0.12065 -0.2794)
			(stroke
				(width 0.1)
				(type default)
			)
			(layer "F.Fab")
		)
		(fp_line
			(start -0.12065 0.2794)
			(end -0.12065 0.3048)
			(stroke
				(width 0.1)
				(type default)
			)
			(layer "F.Fab")
		)
		(fp_line
			(start -0.12065 0.3048)
			(end -0.67945 0.3048)
			(stroke
				(width 0.1)
				(type default)
			)
			(layer "F.Fab")
		)
		(fp_line
			(start 0.120396 0.2794)
			(end -0.12065 0.2794)
			(stroke
				(width 0.1)
				(type default)
			)
			(layer "F.Fab")
		)
		(fp_line
			(start 0.120396 0.3048)
			(end 0.120396 0.2794)
			(stroke
				(width 0.1)
				(type default)
			)
			(layer "F.Fab")
		)
		(fp_line
			(start 0.12065 -0.3048)
			(end 0.67945 -0.3048)
			(stroke
				(width 0.1)
				(type default)
			)
			(layer "F.Fab")
		)
		(fp_line
			(start 0.12065 -0.2794)
			(end 0.12065 -0.3048)
			(stroke
				(width 0.1)
				(type default)
			)
			(layer "F.Fab")
		)
		(fp_line
			(start 0.67945 -0.3048)
			(end 0.67945 0.3048)
			(stroke
				(width 0.1)
				(type default)
			)
			(layer "F.Fab")
		)
		(fp_line
			(start 0.67945 0.3048)
			(end 0.120396 0.3048)
			(stroke
				(width 0.1)
				(type default)
			)
			(layer "F.Fab")
		)
		(pad "1" smd circle
			(at -0.40005 0)
			(size 0 0)
			(layers "F.Cu" "F.Mask" "F.Paste")
			(net "P3V3_AUX")
		)
		(pad "2" smd circle
			(at 0.40005 0)
			(size 0 0)
			(layers "F.Cu" "F.Mask" "F.Paste")
			(net "GND")
		)
	)
	(footprint ""
		(layer "F.Cu")
		(at 256.47269 -39.482522 90)
		(property "Reference" "PC2214"
			(at 0 0 90)
			(layer "F.SilkS")
			(hide yes)
			(effects
				(font
					(size 1.27 1.27)
				)
			)
		)
		(property "Value" ""
			(at 0 0 90)
			(layer "F.Fab")
			(effects
				(font
					(size 1.27 1.27)
				)
			)
		)
		(duplicate_pad_numbers_are_jumpers no)
		(fp_line
			(start 0.7874 -0.4064)
			(end 0.7874 0.4064)
			(stroke
				(width 0.1524)
				(type default)
			)
			(layer "F.SilkS")
		)
		(fp_line
			(start -0.7874 -0.4064)
			(end 0.7874 -0.4064)
			(stroke
				(width 0.1524)
				(type default)
			)
			(layer "F.SilkS")
		)
		(fp_line
			(start 0.7874 0.4064)
			(end -0.7874 0.4064)
			(stroke
				(width 0.1524)
				(type default)
			)
			(layer "F.SilkS")
		)
		(fp_line
			(start -0.7874 0.4064)
			(end -0.7874 -0.4064)
			(stroke
				(width 0.1524)
				(type default)
			)
			(layer "F.SilkS")
		)
		(fp_line
			(start -0.12065 -0.305054)
			(end -0.12065 -0.2794)
			(stroke
				(width 0.1)
				(type default)
			)
			(layer "F.Fab")
		)
		(fp_line
			(start -0.67945 -0.305054)
			(end -0.12065 -0.305054)
			(stroke
				(width 0.1)
				(type default)
			)
			(layer "F.Fab")
		)
		(fp_line
			(start 0.67945 -0.3048)
			(end 0.67945 0.3048)
			(stroke
				(width 0.1)
				(type default)
			)
			(layer "F.Fab")
		)
		(fp_line
			(start 0.12065 -0.3048)
			(end 0.67945 -0.3048)
			(stroke
				(width 0.1)
				(type default)
			)
			(layer "F.Fab")
		)
		(fp_line
			(start 0.12065 -0.2794)
			(end 0.12065 -0.3048)
			(stroke
				(width 0.1)
				(type default)
			)
			(layer "F.Fab")
		)
		(fp_line
			(start -0.12065 -0.2794)
			(end 0.12065 -0.2794)
			(stroke
				(width 0.1)
				(type default)
			)
			(layer "F.Fab")
		)
		(fp_line
			(start 0.120396 0.2794)
			(end -0.12065 0.2794)
			(stroke
				(width 0.1)
				(type default)
			)
			(layer "F.Fab")
		)
		(fp_line
			(start -0.12065 0.2794)
			(end -0.12065 0.3048)
			(stroke
				(width 0.1)
				(type default)
			)
			(layer "F.Fab")
		)
		(fp_line
			(start 0.67945 0.3048)
			(end 0.120396 0.3048)
			(stroke
				(width 0.1)
				(type default)
			)
			(layer "F.Fab")
		)
		(fp_line
			(start 0.120396 0.3048)
			(end 0.120396 0.2794)
			(stroke
				(width 0.1)
				(type default)
			)
			(layer "F.Fab")
		)
		(fp_line
			(start -0.12065 0.3048)
			(end -0.67945 0.3048)
			(stroke
				(width 0.1)
				(type default)
			)
			(layer "F.Fab")
		)
		(fp_line
			(start -0.67945 0.3048)
			(end -0.67945 -0.305054)
			(stroke
				(width 0.1)
				(type default)
			)
			(layer "F.Fab")
		)
		(pad "1" smd circle
			(at -0.40005 0 90)
			(size 0 0)
			(layers "F.Cu" "F.Mask" "F.Paste")
			(net "P12V_E1S_0")
		)
		(pad "2" smd circle
			(at 0.40005 0 90)
			(size 0 0)
			(layers "F.Cu" "F.Mask" "F.Paste")
			(net "P12V_E1S_GATE_0")
		)
	)
)
